# S9S_MB_2U (Grand Teton) — schematic netlist excerpt (pin names and nets, part order shuffled) for the footprints in the layout excerpt that follows; sources: Cadence DE-HDL packaged netlist, KiCad conversion of 03242023_DA0F0TMBIJ0_F0T_Motherboard_J_brd_V01_OCP.brd

R1327  Q_RES  2K 1% EMPTY  pkg 0402LF  page 219 : A = PWRGD_DRAMPWRGD_CPU0_EF_R_LVC1 ; B = GND
PC179  Q_CAP  22UF 16V 20% X6S  pkg C0805  page 276 : A = SW_P12V_PVCCINFAON_CPU0_FLT ; B = GND
R2571  Q_RES  1K 1% CHIP  pkg 0402LF  page 292 : A = P3V3_AUX ; B = PWRGD_PVCCFA_EHV_CPU1_R

(kicad_pcb
	(version 20260206)
	(generator "pcbnew")
	(generator_version "10.0")
	(general
		(thickness 1.6)
		(legacy_teardrops no)
	)
	(paper "A4")
	(title_block
		(title "03242023_DA0F0TMBIJ0_F0T_Motherboard_J_brd_V01_OCP.brd")
		(comment 1 "Grand Teton / footprints 4830-4832 of 6105")
	)
	(layers
		(0 "F.Cu" signal "TOP")
		(4 "In1.Cu" signal "GND")
		(6 "In2.Cu" signal "IN1")
		(8 "In3.Cu" signal "GND1")
		(10 "In4.Cu" signal "IN2")
		(12 "In5.Cu" signal "GND2")
		(14 "In6.Cu" signal "IN3")
		(16 "In7.Cu" signal "GND3")
		(18 "In8.Cu" signal "VCC")
		(20 "In9.Cu" signal "VCC1")
		(22 "In10.Cu" signal "GND4")
		(24 "In11.Cu" signal "IN4")
		(26 "In12.Cu" signal "GND5")
		(28 "In13.Cu" signal "IN5")
		(30 "In14.Cu" signal "GND6")
		(32 "In15.Cu" signal "IN6")
		(34 "In16.Cu" signal "GND7")
		(2 "B.Cu" signal "BOTTOM")
		(9 "F.Adhes" user "F.Adhesive")
		(11 "B.Adhes" user "B.Adhesive")
		(13 "F.Paste" user "Package Geometry/Pastemask Top")
		(15 "B.Paste" user "Package Geometry/Pastemask Bottom")
		(5 "F.SilkS" user "Ref Des/Silkscreen Top")
		(7 "B.SilkS" user "Ref Des/Silkscreen Bottom")
		(1 "F.Mask" user "Board Geometry/Soldermask Top")
		(3 "B.Mask" user "Board Geometry/Soldermask Bottom")
		(17 "Dwgs.User" user "User.Drawings")
		(19 "Cmts.User" user "User.Comments")
		(21 "Eco1.User" user "User.Eco1")
		(23 "Eco2.User" user "User.Eco2")
		(25 "Edge.Cuts" user "Board Geometry/Outline")
		(27 "Margin" user)
		(31 "F.CrtYd" user "Package Geometry/Place Bound Top")
		(29 "B.CrtYd" user "Package Geometry/Place Bound Bottom")
		(35 "F.Fab" user "Ref Des/Assembly Top")
		(33 "B.Fab" user "Ref Des/Assembly Bottom")
	)
	(footprint ""
		(layer "B.Cu")
		(at 418.57549 -149.950424)
		(property "Reference" "PC179"
			(at 0 0 0)
			(layer "B.SilkS")
			(hide yes)
			(effects
				(font
					(size 1.27 1.27)
				)
				(justify mirror)
			)
		)
		(property "Value" ""
			(at 0 0 0)
			(layer "B.Fab")
			(effects
				(font
					(size 1.27 1.27)
				)
				(justify mirror)
			)
		)
		(duplicate_pad_numbers_are_jumpers no)
		(fp_line
			(start -1.524 -0.762)
			(end -1.524 0.762)
			(stroke
				(width 0.1524)
				(type default)
			)
			(layer "B.SilkS")
		)
		(fp_line
			(start -1.524 0.762)
			(end 1.524 0.762)
			(stroke
				(width 0.1524)
				(type default)
			)
			(layer "B.SilkS")
		)
		(fp_line
			(start 1.524 -0.762)
			(end -1.524 -0.762)
			(stroke
				(width 0.1524)
				(type default)
			)
			(layer "B.SilkS")
		)
		(fp_line
			(start 1.524 0.762)
			(end 1.524 -0.762)
			(stroke
				(width 0.1524)
				(type default)
			)
			(layer "B.SilkS")
		)
		(fp_line
			(start -1.1049 -0.724916)
			(end 1.1049 -0.724916)
			(stroke
				(width 0.1)
				(type default)
			)
			(layer "B.Fab")
		)
		(fp_line
			(start -1.1049 0.724916)
			(end -1.1049 -0.724916)
			(stroke
				(width 0.1)
				(type default)
			)
			(layer "B.Fab")
		)
		(fp_line
			(start 1.1049 -0.724916)
			(end 1.1049 0.724916)
			(stroke
				(width 0.1)
				(type default)
			)
			(layer "B.Fab")
		)
		(fp_line
			(start 1.1049 0.724916)
			(end -1.1049 0.724916)
			(stroke
				(width 0.1)
				(type default)
			)
			(layer "B.Fab")
		)
		(pad "1" smd rect
			(at 0.889 0)
			(size 1.016 1.27)
			(layers "B.Cu" "B.Mask" "B.Paste")
			(net "SW_P12V_PVCCINFAON_CPU0_FLT")
		)
		(pad "2" smd rect
			(at -0.889 0)
			(size 1.016 1.27)
			(layers "B.Cu" "B.Mask" "B.Paste")
			(net "GND")
		)
	)
	(footprint ""
		(layer "B.Cu")
		(at 36.956238 -130.80492)
		(property "Reference" "R2571"
			(at 0 0 0)
			(layer "B.SilkS")
			(hide yes)
			(effects
				(font
					(size 1.27 1.27)
				)
				(justify mirror)
			)
		)
		(property "Value" ""
			(at 0 0 0)
			(layer "B.Fab")
			(effects
				(font
					(size 1.27 1.27)
				)
				(justify mirror)
			)
		)
		(duplicate_pad_numbers_are_jumpers no)
		(fp_line
			(start -0.7874 -0.4064)
			(end -0.7874 0.4064)
			(stroke
				(width 0.1524)
				(type default)
			)
			(layer "B.SilkS")
		)
		(fp_line
			(start -0.7874 0.4064)
			(end 0.7874 0.4064)
			(stroke
				(width 0.1524)
				(type default)
			)
			(layer "B.SilkS")
		)
		(fp_line
			(start 0.7874 -0.4064)
			(end -0.7874 -0.4064)
			(stroke
				(width 0.1524)
				(type default)
			)
			(layer "B.SilkS")
		)
		(fp_line
			(start 0.7874 0.4064)
			(end 0.7874 -0.4064)
			(stroke
				(width 0.1524)
				(type default)
			)
			(layer "B.SilkS")
		)
		(fp_line
			(start -0.67945 -0.3048)
			(end -0.67945 0.3048)
			(stroke
				(width 0.1)
				(type default)
			)
			(layer "B.Fab")
		)
		(fp_line
			(start -0.67945 0.3048)
			(end -0.120396 0.3048)
			(stroke
				(width 0.1)
				(type default)
			)
			(layer "B.Fab")
		)
		(fp_line
			(start -0.12065 -0.3048)
			(end -0.67945 -0.3048)
			(stroke
				(width 0.1)
				(type default)
			)
			(layer "B.Fab")
		)
		(fp_line
			(start -0.12065 -0.2794)
			(end -0.12065 -0.3048)
			(stroke
				(width 0.1)
				(type default)
			)
			(layer "B.Fab")
		)
		(fp_line
			(start -0.120396 0.2794)
			(end 0.12065 0.2794)
			(stroke
				(width 0.1)
				(type default)
			)
			(layer "B.Fab")
		)
		(fp_line
			(start -0.120396 0.3048)
			(end -0.120396 0.2794)
			(stroke
				(width 0.1)
				(type default)
			)
			(layer "B.Fab")
		)
		(fp_line
			(start 0.12065 -0.305054)
			(end 0.12065 -0.2794)
			(stroke
				(width 0.1)
				(type default)
			)
			(layer "B.Fab")
		)
		(fp_line
			(start 0.12065 -0.2794)
			(end -0.12065 -0.2794)
			(stroke
				(width 0.1)
				(type default)
			)
			(layer "B.Fab")
		)
		(fp_line
			(start 0.12065 0.2794)
			(end 0.12065 0.3048)
			(stroke
				(width 0.1)
				(type default)
			)
			(layer "B.Fab")
		)
		(fp_line
			(start 0.12065 0.3048)
			(end 0.67945 0.3048)
			(stroke
				(width 0.1)
				(type default)
			)
			(layer "B.Fab")
		)
		(fp_line
			(start 0.67945 -0.305054)
			(end 0.12065 -0.305054)
			(stroke
				(width 0.1)
				(type default)
			)
			(layer "B.Fab")
		)
		(fp_line
			(start 0.67945 0.3048)
			(end 0.67945 -0.305054)
			(stroke
				(width 0.1)
				(type default)
			)
			(layer "B.Fab")
		)
		(pad "1" smd circle
			(at 0.40005 0 180)
			(size 0 0)
			(layers "B.Cu" "B.Mask" "B.Paste")
			(net "P3V3_AUX")
		)
		(pad "2" smd circle
			(at -0.40005 0 180)
			(size 0 0)
			(layers "B.Cu" "B.Mask" "B.Paste")
			(net "PWRGD_PVCCFA_EHV_CPU1_R")
		)
	)
	(footprint ""
		(layer "B.Cu")
		(at 178.05019 -107.07116 180)
		(property "Reference" "R1327"
			(at 0 0 0)
			(layer "B.SilkS")
			(hide yes)
			(effects
				(font
					(size 1.27 1.27)
				)
				(justify mirror)
			)
		)
		(property "Value" ""
			(at 0 0 0)
			(layer "B.Fab")
			(effects
				(font
					(size 1.27 1.27)
				)
				(justify mirror)
			)
		)
		(duplicate_pad_numbers_are_jumpers no)
		(fp_line
			(start 0.7874 0.4064)
			(end 0.7874 -0.4064)
			(stroke
				(width 0.1524)
				(type default)
			)
			(layer "B.SilkS")
		)
		(fp_line
			(start 0.7874 -0.4064)
			(end -0.7874 -0.4064)
			(stroke
				(width 0.1524)
				(type default)
			)
			(layer "B.SilkS")
		)
		(fp_line
			(start -0.7874 0.4064)
			(end 0.7874 0.4064)
			(stroke
				(width 0.1524)
				(type default)
			)
			(layer "B.SilkS")
		)
		(fp_line
			(start -0.7874 -0.4064)
			(end -0.7874 0.4064)
			(stroke
				(width 0.1524)
				(type default)
			)
			(layer "B.SilkS")
		)
		(fp_line
			(start 0.67945 0.3048)
			(end 0.67945 -0.305054)
			(stroke
				(width 0.1)
				(type default)
			)
			(layer "B.Fab")
		)
		(fp_line
			(start 0.67945 -0.305054)
			(end 0.12065 -0.305054)
			(stroke
				(width 0.1)
				(type default)
			)
			(layer "B.Fab")
		)
		(fp_line
			(start 0.12065 0.3048)
			(end 0.67945 0.3048)
			(stroke
				(width 0.1)
				(type default)
			)
			(layer "B.Fab")
		)
		(fp_line
			(start 0.12065 0.2794)
			(end 0.12065 0.3048)
			(stroke
				(width 0.1)
				(type default)
			)
			(layer "B.Fab")
		)
		(fp_line
			(start 0.12065 -0.2794)
			(end -0.12065 -0.2794)
			(stroke
				(width 0.1)
				(type default)
			)
			(layer "B.Fab")
		)
		(fp_line
			(start 0.12065 -0.305054)
			(end 0.12065 -0.2794)
			(stroke
				(width 0.1)
				(type default)
			)
			(layer "B.Fab")
		)
		(fp_line
			(start -0.120396 0.3048)
			(end -0.120396 0.2794)
			(stroke
				(width 0.1)
				(type default)
			)
			(layer "B.Fab")
		)
		(fp_line
			(start -0.120396 0.2794)
			(end 0.12065 0.2794)
			(stroke
				(width 0.1)
				(type default)
			)
			(layer "B.Fab")
		)
		(fp_line
			(start -0.12065 -0.2794)
			(end -0.12065 -0.3048)
			(stroke
				(width 0.1)
				(type default)
			)
			(layer "B.Fab")
		)
		(fp_line
			(start -0.12065 -0.3048)
			(end -0.67945 -0.3048)
			(stroke
				(width 0.1)
				(type default)
			)
			(layer "B.Fab")
		)
		(fp_line
			(start -0.67945 0.3048)
			(end -0.120396 0.3048)
			(stroke
				(width 0.1)
				(type default)
			)
			(layer "B.Fab")
		)
		(fp_line
			(start -0.67945 -0.3048)
			(end -0.67945 0.3048)
			(stroke
				(width 0.1)
				(type default)
			)
			(layer "B.Fab")
		)
		(pad "1" smd circle
			(at 0.40005 0)
			(size 0 0)
			(layers "B.Cu" "B.Mask" "B.Paste")
			(net "PWRGD_DRAMPWRGD_CPU0_EF_R_LVC1")
		)
		(pad "2" smd circle
			(at -0.40005 0)
			(size 0 0)
			(layers "B.Cu" "B.Mask" "B.Paste")
			(net "GND")
		)
	)
)
